FILE_TYPE = MACRO_DRAWING;
SET COLOR_WIRE YELLOW;
SET COLOR_PROP ORANGE;
SET COLOR_DOT WHITE;
SET COLOR_ARC YELLOW;
SET COLOR_BODY GREEN;
SET COLOR_NOTE PURPLE;
SET PROP_DISPLAY VALUE;
SET PAGE_NUMBER P2;
SET PATH_NUMBER P0;
FORCEADD QUANTA_TITLE_BLOCK_C..2
(5625 -1650);
FORCEPROP 0 LAST CDS_CON_LAST_MODIFIED Fri Aug 25 17:25:34 2023
J 0
(3725 -1625);
DISPLAY INVISIBLE (3725 -1625);
FORCEPROP 2 LAST Q_DEPT 
J 1
(1874 -1601);
DISPLAY 1.957447 (1874 -1601);
PAINT GREEN (1874 -1601);
FORCEPROP 2 LAST CUSTOM_TXT_CDS <XR_PAGE_TITLE>
J 0
(-2265 3600);
DISPLAY 0.638298 (-2265 3600);
PAINT PINK (-2265 3600);
DISPLAY INVISIBLE (-2265 3600);
FORCEPROP 1 LAST Q_TITLE INDEX
J 0
(-3691 -1599);
DISPLAY 2.446809 (-3691 -1599);
PAINT GREEN (-3691 -1599);
FORCEPROP 2 LAST PAGE_BORDER TRUE
J 0
(-2265 3600);
DISPLAY 0.638298 (-2265 3600);
PAINT PINK (-2265 3600);
DISPLAY INVISIBLE (-2265 3600);
FORCEPROP 1 LAST TOC_SYMBOL TRUE
J 0
(-3549 4802);
DISPLAY 0.978723 (-3549 4802);
PAINT GREEN (-3549 4802);
DISPLAY INVISIBLE (-3549 4802);
FORCEPROP 2 LAST CDS_LIB pure_quanta
J 0
(5625 -1650);
DISPLAY INVISIBLE (5625 -1650);
FORCEPROP 1 LAST CDS_LMAN_SYM_OUTLINE -9450,6750,100,-100
J 0
(5625 -1650);
DISPLAY 0.468085 (5625 -1650);
PAINT GREEN (5625 -1650);
DISPLAY INVISIBLE (5625 -1650);
FORCEPROP 1 LAST COMMENT_BODY TRUE
J 0
(4476 -1624);
DISPLAY 0.978723 (4476 -1624);
PAINT PEACH (4476 -1624);
DISPLAY INVISIBLE (4476 -1624);
FORCEPROP 2 LAST CDS_XR_PAGE_TITLE CR-2 : @SCM_LIB.SCM(SCH_1):PAGE2
J 0
(-2265 3600);
DISPLAY 0.638298 (-2265 3600);
PAINT PINK (-2265 3600);
DISPLAY INVISIBLE (-2265 3600);
QUIT
